(kicad_pcb
	(version 20240108)
	(generator "pcbnew")
	(generator_version "8.0")
	(general
		(thickness 1.62)
		(legacy_teardrops no)
	)
	(paper "A4")
	(title_block
		(title "Jetson Orin Baseboard")
		(date "2025-03-12")
		(rev "1.3.4")
		(company "Antmicro Ltd")
		(comment 1 "www.antmicro.com")
		(comment 9 "footprints 600-603 of 677")
	)
	(layers
		(0 "F.Cu" signal)
		(1 "In1.Cu" signal)
		(2 "In2.Cu" signal)
		(3 "In3.Cu" signal)
		(4 "In4.Cu" jumper)
		(5 "In5.Cu" signal)
		(6 "In6.Cu" signal)
		(31 "B.Cu" signal)
		(32 "B.Adhes" user "B.Adhesive")
		(33 "F.Adhes" user "F.Adhesive")
		(34 "B.Paste" user)
		(35 "F.Paste" user)
		(36 "B.SilkS" user "B.Silkscreen")
		(37 "F.SilkS" user "F.Silkscreen")
		(38 "B.Mask" user)
		(39 "F.Mask" user)
		(40 "Dwgs.User" user "User.Drawings")
		(41 "Cmts.User" user "User.Comments")
		(42 "Eco1.User" user "User.Eco1")
		(43 "Eco2.User" user "User.Eco2")
		(44 "Edge.Cuts" user)
		(45 "Margin" user)
		(46 "B.CrtYd" user "B.Courtyard")
		(47 "F.CrtYd" user "F.Courtyard")
		(48 "B.Fab" user)
		(49 "F.Fab" user)
	)
	(footprint "antmicro-footprints:SOT-523"
		(layer "B.Cu")
		(at 61 73.1 90)
		(property "Reference" "Q7"
			(at 1.01 0.71 0)
			(layer "B.SilkS")
			(effects
				(font
					(size 0.7 0.7)
					(thickness 0.15)
				)
				(justify left bottom mirror)
			)
		)
		(property "Value" "PJE138K"
			(at 0.1 -1.824 -90)
			(layer "B.Fab")
			(effects
				(font
					(size 0.7 0.7)
					(thickness 0.15)
				)
				(justify left bottom mirror)
			)
		)
		(property "Footprint" "antmicro-footprints:SOT-523"
			(at 0 0 90)
			(layer "F.Fab")
			(hide yes)
			(effects
				(font
					(size 1.27 1.27)
					(thickness 0.15)
				)
			)
		)
		(property "Datasheet" "https://www.mouser.com/datasheet/2/1057/PJE138K-1876698.pdf"
			(at 0 0 90)
			(layer "F.Fab")
			(hide yes)
			(effects
				(font
					(size 1.27 1.27)
					(thickness 0.15)
				)
			)
		)
		(property "Author" "Antmicro"
			(at 134.1 12.1 0)
			(layer "B.Fab")
			(hide yes)
			(effects
				(font
					(size 1 1)
					(thickness 0.15)
				)
				(justify mirror)
			)
		)
		(property "License" "Apache-2.0"
			(at 134.1 12.1 0)
			(layer "B.Fab")
			(hide yes)
			(effects
				(font
					(size 1 1)
					(thickness 0.15)
				)
				(justify mirror)
			)
		)
		(property "MPN" "PJE138K_R1_00001"
			(at 134.1 12.1 0)
			(layer "B.Fab")
			(hide yes)
			(effects
				(font
					(size 1 1)
					(thickness 0.15)
				)
				(justify mirror)
			)
		)
		(property "Manufacturer" "PANJIT"
			(at 134.1 12.1 0)
			(layer "B.Fab")
			(hide yes)
			(effects
				(font
					(size 1 1)
					(thickness 0.15)
				)
				(justify mirror)
			)
		)
		(sheetname "Supply")
		(sheetfile "supply.kicad_sch")
		(attr smd)
		(fp_line
			(start -0.927 0.351)
			(end -0.927 0.051)
			(stroke
				(width 0.15)
				(type solid)
			)
			(layer "B.SilkS")
		)
		(fp_line
			(start -0.277 0.551)
			(end -0.725 0.551)
			(stroke
				(width 0.15)
				(type solid)
			)
			(layer "B.SilkS")
		)
		(fp_line
			(start -0.725 0.551)
			(end -0.927 0.351)
			(stroke
				(width 0.15)
				(type solid)
			)
			(layer "B.SilkS")
		)
		(fp_line
			(start -0.277 0.75)
			(end -0.277 0.551)
			(stroke
				(width 0.15)
				(type solid)
			)
			(layer "B.SilkS")
		)
		(fp_circle
			(center -0.9652 -0.9652)
			(end -0.9152 -0.9652)
			(stroke
				(width 0.15)
				(type solid)
			)
			(fill solid)
			(layer "B.SilkS")
		)
		(fp_line
			(start 1.1 -1.15)
			(end -1.12 -1.15)
			(stroke
				(width 0.05)
				(type solid)
			)
			(layer "B.CrtYd")
		)
		(fp_line
			(start 1.1 -1.15)
			(end 1.1 1.16)
			(stroke
				(width 0.05)
				(type solid)
			)
			(layer "B.CrtYd")
		)
		(fp_line
			(start -1.12 -1.15)
			(end -1.12 1.16)
			(stroke
				(width 0.05)
				(type solid)
			)
			(layer "B.CrtYd")
		)
		(fp_line
			(start 1.1 1.16)
			(end -1.12 1.16)
			(stroke
				(width 0.05)
				(type solid)
			)
			(layer "B.CrtYd")
		)
		(fp_line
			(start 0.8 -0.424)
			(end 0.8 0.425)
			(stroke
				(width 0.15)
				(type solid)
			)
			(layer "B.Fab")
		)
		(fp_line
			(start -0.802 -0.424)
			(end 0.8 -0.424)
			(stroke
				(width 0.15)
				(type solid)
			)
			(layer "B.Fab")
		)
		(fp_line
			(start -0.802 -0.424)
			(end -0.802 0.276)
			(stroke
				(width 0.15)
				(type solid)
			)
			(layer "B.Fab")
		)
		(fp_line
			(start -0.802 0.276)
			(end -0.652 0.425)
			(stroke
				(width 0.15)
				(type solid)
			)
			(layer "B.Fab")
		)
		(fp_line
			(start -0.652 0.425)
			(end 0.8 0.425)
			(stroke
				(width 0.15)
				(type solid)
			)
			(layer "B.Fab")
		)
		(fp_circle
			(center -0.9652 -0.9652)
			(end -0.9144 -0.9652)
			(stroke
				(width 0.15)
				(type solid)
			)
			(fill none)
			(layer "B.Fab")
		)
		(fp_text user "${REFERENCE}"
			(at -1.12 -3.824 -90)
			(layer "B.Fab")
			(hide yes)
			(effects
				(font
					(size 0.7 0.7)
					(thickness 0.15)
				)
				(justify left bottom mirror)
			)
		)
		(fp_text user "Author: Antmicro"
			(at -1.12 -6.224 -90)
			(layer "B.Fab")
			(hide yes)
			(effects
				(font
					(size 0.7 0.7)
					(thickness 0.15)
				)
				(justify left bottom mirror)
			)
		)
		(fp_text user "License: Apache-2.0"
			(at -1.12 -5.024 -90)
			(layer "B.Fab")
			(hide yes)
			(effects
				(font
					(size 0.7 0.7)
					(thickness 0.15)
				)
				(justify left bottom mirror)
			)
		)
		(pad "1" smd rect
			(at -0.5 -0.65 90)
			(size 0.4 0.51)
			(layers "B.Cu" "B.Paste" "B.Mask")
			(net 279 "PWR_SOFT")
			(pinfunction "G")
			(pintype "passive")
		)
		(pad "2" smd rect
			(at 0.498 -0.65 90)
			(size 0.4 0.51)
			(layers "B.Cu" "B.Paste" "B.Mask")
			(net 1 "GND")
			(pinfunction "S")
			(pintype "passive")
		)
		(pad "3" smd rect
			(at 0 0.652 90)
			(size 0.4 0.51)
			(layers "B.Cu" "B.Paste" "B.Mask")
			(net 137 "Net-(D36-A)")
			(pinfunction "D")
			(pintype "passive")
		)
	)
	(footprint "antmicro-footprints:C_0402_1005Metric"
		(layer "B.Cu")
		(at 68.2 108.2 -90)
		(descr "Capacitor SMD 0402")
		(tags "capacitor SMD 0402")
		(property "Reference" "C65"
			(at -0.89 -1.31 90)
			(layer "B.SilkS")
			(effects
				(font
					(size 0.7 0.7)
					(thickness 0.15)
				)
				(justify left bottom mirror)
			)
		)
		(property "Value" "C_100n_0402"
			(at 0 -1.4 90)
			(layer "B.Fab")
			(effects
				(font
					(size 0.7 0.7)
					(thickness 0.15)
				)
				(justify left bottom mirror)
			)
		)
		(property "Footprint" "antmicro-footprints:C_0402_1005Metric"
			(at 0 0 -90)
			(layer "F.Fab")
			(hide yes)
			(effects
				(font
					(size 1.27 1.27)
					(thickness 0.15)
				)
			)
		)
		(property "Datasheet" "https://www.murata.com/products/productdetail?partno=GRM155R61H104KE14%23"
			(at 0 0 -90)
			(layer "F.Fab")
			(hide yes)
			(effects
				(font
					(size 1.27 1.27)
					(thickness 0.15)
				)
			)
		)
		(property "Author" "Antmicro"
			(at -40 176.4 0)
			(layer "B.Fab")
			(hide yes)
			(effects
				(font
					(size 1 1)
					(thickness 0.15)
				)
				(justify mirror)
			)
		)
		(property "Dielectric" "X5R"
			(at -40 176.4 0)
			(layer "B.Fab")
			(hide yes)
			(effects
				(font
					(size 1 1)
					(thickness 0.15)
				)
				(justify mirror)
			)
		)
		(property "License" "Apache-2.0"
			(at -40 176.4 0)
			(layer "B.Fab")
			(hide yes)
			(effects
				(font
					(size 1 1)
					(thickness 0.15)
				)
				(justify mirror)
			)
		)
		(property "MPN" "GRM155R61H104KE14D"
			(at -40 176.4 0)
			(layer "B.Fab")
			(hide yes)
			(effects
				(font
					(size 1 1)
					(thickness 0.15)
				)
				(justify mirror)
			)
		)
		(property "Manufacturer" "Murata"
			(at -40 176.4 0)
			(layer "B.Fab")
			(hide yes)
			(effects
				(font
					(size 1 1)
					(thickness 0.15)
				)
				(justify mirror)
			)
		)
		(property "Val" "100n"
			(at -40 176.4 0)
			(layer "B.Fab")
			(hide yes)
			(effects
				(font
					(size 1 1)
					(thickness 0.15)
				)
				(justify mirror)
			)
		)
		(property "Voltage" "50V"
			(at -40 176.4 0)
			(layer "B.Fab")
			(hide yes)
			(effects
				(font
					(size 1 1)
					(thickness 0.15)
				)
				(justify mirror)
			)
		)
		(sheetname "USB Debug, DP")
		(sheetfile "usb.kicad_sch")
		(attr smd)
		(fp_rect
			(start -0.925 0.47)
			(end 0.925 -0.47)
			(stroke
				(width 0.05)
				(type default)
			)
			(fill none)
			(layer "B.CrtYd")
		)
		(fp_line
			(start -0.494 0.25)
			(end -0.494 -0.248)
			(stroke
				(width 0.15)
				(type solid)
			)
			(layer "B.Fab")
		)
		(fp_line
			(start 0.504 0.25)
			(end -0.494 0.25)
			(stroke
				(width 0.15)
				(type solid)
			)
			(layer "B.Fab")
		)
		(fp_line
			(start -0.494 -0.248)
			(end 0.504 -0.248)
			(stroke
				(width 0.15)
				(type solid)
			)
			(layer "B.Fab")
		)
		(fp_line
			(start 0.504 -0.248)
			(end 0.504 0.25)
			(stroke
				(width 0.15)
				(type solid)
			)
			(layer "B.Fab")
		)
		(fp_text user "License: Apache-2.0"
			(at -0.932 -5.17 90)
			(layer "B.Fab")
			(hide yes)
			(effects
				(font
					(size 0.7 0.7)
					(thickness 0.15)
				)
				(justify left bottom mirror)
			)
		)
		(fp_text user "${REFERENCE}"
			(at -0.932 -3.168 90)
			(layer "B.Fab")
			(hide yes)
			(effects
				(font
					(size 0.7 0.7)
					(thickness 0.15)
				)
				(justify left bottom mirror)
			)
		)
		(fp_text user "Author: Antmicro"
			(at -0.932 -4.17 90)
			(layer "B.Fab")
			(hide yes)
			(effects
				(font
					(size 0.7 0.7)
					(thickness 0.15)
				)
				(justify left bottom mirror)
			)
		)
		(pad "1" smd roundrect
			(at -0.48 0 270)
			(size 0.59 0.64)
			(layers "B.Cu" "B.Paste" "B.Mask")
			(roundrect_rratio 0.25)
			(net 261 "/USB Debug, DP/USBC0_VBUS")
			(pintype "passive")
		)
		(pad "2" smd roundrect
			(at 0.48 0 270)
			(size 0.59 0.64)
			(layers "B.Cu" "B.Paste" "B.Mask")
			(roundrect_rratio 0.25)
			(net 1 "GND")
			(pintype "passive")
		)
	)
	(footprint "antmicro-footprints:R_0402_1005Metric"
		(layer "B.Cu")
		(at 72.3 75.7 90)
		(descr "Resistor SMD 0402")
		(tags "resistor SMD 0402")
		(property "Reference" "R261"
			(at -2.3 14.41 -90)
			(layer "B.SilkS")
			(effects
				(font
					(size 0.7 0.7)
					(thickness 0.15)
				)
				(justify left bottom mirror)
			)
		)
		(property "Value" "R_200k_0402"
			(at 0 -1.4 -90)
			(layer "B.Fab")
			(effects
				(font
					(size 0.7 0.7)
					(thickness 0.15)
				)
				(justify left bottom mirror)
			)
		)
		(property "Footprint" "antmicro-footprints:R_0402_1005Metric"
			(at 0 0 90)
			(layer "F.Fab")
			(hide yes)
			(effects
				(font
					(size 1.27 1.27)
					(thickness 0.15)
				)
			)
		)
		(property "Datasheet" "https://www.bourns.com/docs/product-datasheets/cr.pdf"
			(at 0 0 90)
			(layer "F.Fab")
			(hide yes)
			(effects
				(font
					(size 1.27 1.27)
					(thickness 0.15)
				)
			)
		)
		(property "Author" "Antmicro"
			(at 148 3.4 0)
			(layer "B.Fab")
			(hide yes)
			(effects
				(font
					(size 1 1)
					(thickness 0.15)
				)
				(justify mirror)
			)
		)
		(property "License" "Apache-2.0"
			(at 148 3.4 0)
			(layer "B.Fab")
			(hide yes)
			(effects
				(font
					(size 1 1)
					(thickness 0.15)
				)
				(justify mirror)
			)
		)
		(property "MPN" "CR0402-FX-2003GLF"
			(at 148 3.4 0)
			(layer "B.Fab")
			(hide yes)
			(effects
				(font
					(size 1 1)
					(thickness 0.15)
				)
				(justify mirror)
			)
		)
		(property "Manufacturer" "Bourns"
			(at 148 3.4 0)
			(layer "B.Fab")
			(hide yes)
			(effects
				(font
					(size 1 1)
					(thickness 0.15)
				)
				(justify mirror)
			)
		)
		(property "Tolerance" "1%"
			(at 148 3.4 0)
			(layer "B.Fab")
			(hide yes)
			(effects
				(font
					(size 1 1)
					(thickness 0.15)
				)
				(justify mirror)
			)
		)
		(property "Val" "200k"
			(at 148 3.4 0)
			(layer "B.Fab")
			(hide yes)
			(effects
				(font
					(size 1 1)
					(thickness 0.15)
				)
				(justify mirror)
			)
		)
		(sheetname "Supply")
		(sheetfile "supply.kicad_sch")
		(attr smd)
		(fp_rect
			(start -0.925 0.47)
			(end 0.925 -0.47)
			(stroke
				(width 0.05)
				(type default)
			)
			(fill none)
			(layer "B.CrtYd")
		)
		(fp_rect
			(start -0.5 0.25)
			(end 0.5 -0.25)
			(stroke
				(width 0.15)
				(type solid)
			)
			(fill none)
			(layer "B.Fab")
		)
		(fp_text user "License: Apache-2.0"
			(at -0.95 -5.169 -90)
			(layer "B.Fab")
			(hide yes)
			(effects
				(font
					(size 0.7 0.7)
					(thickness 0.15)
				)
				(justify left bottom mirror)
			)
		)
		(fp_text user "${REFERENCE}"
			(at -0.95 -3.168 -90)
			(layer "B.Fab")
			(hide yes)
			(effects
				(font
					(size 0.7 0.7)
					(thickness 0.15)
				)
				(justify left bottom mirror)
			)
		)
		(fp_text user "Author: Antmicro"
			(at -0.95 -4.169 -90)
			(layer "B.Fab")
			(hide yes)
			(effects
				(font
					(size 0.7 0.7)
					(thickness 0.15)
				)
				(justify left bottom mirror)
			)
		)
		(pad "1" smd roundrect
			(at -0.48 0 90)
			(size 0.59 0.64)
			(layers "B.Cu" "B.Paste" "B.Mask")
			(roundrect_rratio 0.25)
			(net 1 "GND")
			(pintype "passive")
		)
		(pad "2" smd roundrect
			(at 0.48 0 90)
			(size 0.59 0.64)
			(layers "B.Cu" "B.Paste" "B.Mask")
			(roundrect_rratio 0.25)
			(net 179 "Net-(D61-A)")
			(pintype "passive")
		)
	)
	(footprint "antmicro-footprints:TSOT23-6"
		(layer "B.Cu")
		(at 137.53 113.95 -90)
		(property "Reference" "U24"
			(at -2 1.08 0)
			(layer "B.SilkS")
			(effects
				(font
					(size 0.7 0.7)
					(thickness 0.15)
				)
				(justify right bottom mirror)
			)
		)
		(property "Value" "AP22615A_TSOT26"
			(at 0 -2.6 90)
			(layer "B.Fab")
			(effects
				(font
					(size 0.7 0.7)
					(thickness 0.15)
				)
				(justify left bottom mirror)
			)
		)
		(property "Footprint" "antmicro-footprints:TSOT23-6"
			(at 0 0 -90)
			(layer "F.Fab")
			(hide yes)
			(effects
				(font
					(size 1.27 1.27)
					(thickness 0.15)
				)
			)
		)
		(property "Datasheet" "https://www.mouser.com/datasheet/2/115/DIOD_S_A0008958405_1-2543193.pdf"
			(at 0 0 -90)
			(layer "F.Fab")
			(hide yes)
			(effects
				(font
					(size 1.27 1.27)
					(thickness 0.15)
				)
			)
		)
		(property "Author" "Antmicro"
			(at 23.58 251.48 0)
			(layer "B.Fab")
			(hide yes)
			(effects
				(font
					(size 1 1)
					(thickness 0.15)
				)
				(justify mirror)
			)
		)
		(property "License" "Apache-2.0"
			(at 23.58 251.48 0)
			(layer "B.Fab")
			(hide yes)
			(effects
				(font
					(size 1 1)
					(thickness 0.15)
				)
				(justify mirror)
			)
		)
		(property "MPN" "AP22615AWU-7"
			(at 23.58 251.48 0)
			(layer "B.Fab")
			(hide yes)
			(effects
				(font
					(size 1 1)
					(thickness 0.15)
				)
				(justify mirror)
			)
		)
		(property "Manufacturer" "Diodes Incorporated"
			(at 23.58 251.48 0)
			(layer "B.Fab")
			(hide yes)
			(effects
				(font
					(size 1 1)
					(thickness 0.15)
				)
				(justify mirror)
			)
		)
		(sheetname "CSI")
		(sheetfile "csi.kicad_sch")
		(attr smd)
		(fp_line
			(start -1 1.5)
			(end 1 1.497)
			(stroke
				(width 0.15)
				(type solid)
			)
			(layer "B.SilkS")
		)
		(fp_line
			(start -1 1.375)
			(end -1 1.5)
			(stroke
				(width 0.15)
				(type solid)
			)
			(layer "B.SilkS")
		)
		(fp_line
			(start 1 1.375)
			(end 1 1.497)
			(stroke
				(width 0.15)
				(type solid)
			)
			(layer "B.SilkS")
		)
		(fp_line
			(start -1 -1.4)
			(end -1 -1.55)
			(stroke
				(width 0.15)
				(type solid)
			)
			(layer "B.SilkS")
		)
		(fp_line
			(start 1 -1.4)
			(end 1 -1.55)
			(stroke
				(width 0.15)
				(type solid)
			)
			(layer "B.SilkS")
		)
		(fp_line
			(start -1 -1.55)
			(end 1 -1.55)
			(stroke
				(width 0.15)
				(type solid)
			)
			(layer "B.SilkS")
		)
		(fp_circle
			(center -1.44 1.5)
			(end -1.39 1.5)
			(stroke
				(width 0.15)
				(type solid)
			)
			(fill solid)
			(layer "B.SilkS")
		)
		(fp_rect
			(start 1.93 1.7)
			(end -1.93 -1.7)
			(stroke
				(width 0.05)
				(type solid)
			)
			(fill none)
			(layer "B.CrtYd")
		)
		(fp_line
			(start -0.876 1.096)
			(end -0.45 1.521)
			(stroke
				(width 0.15)
				(type solid)
			)
			(layer "B.Fab")
		)
		(fp_rect
			(start 0.875 -1.528)
			(end -0.875 1.525)
			(stroke
				(width 0.15)
				(type solid)
			)
			(fill none)
			(layer "B.Fab")
		)
		(fp_text user "${REFERENCE}"
			(at -1.93 -3.8 90)
			(layer "B.Fab")
			(hide yes)
			(effects
				(font
					(size 0.7 0.7)
					(thickness 0.15)
				)
				(justify left bottom mirror)
			)
		)
		(fp_text user "License: Apache-2.0"
			(at -1.93 -6.199 90)
			(layer "B.Fab")
			(hide yes)
			(effects
				(font
					(size 0.7 0.7)
					(thickness 0.15)
				)
				(justify left bottom mirror)
			)
		)
		(fp_text user "Author: Antmicro"
			(at -1.93 -5 90)
			(layer "B.Fab")
			(hide yes)
			(effects
				(font
					(size 0.7 0.7)
					(thickness 0.15)
				)
				(justify left bottom mirror)
			)
		)
		(pad "1" smd rect
			(at -1.301 0.947)
			(size 0.7 1.2)
			(layers "B.Cu" "B.Paste" "B.Mask")
			(net 109 "/CSI/CSIA_5V")
			(pinfunction "OUT")
			(pintype "power_out")
		)
		(pad "2" smd rect
			(at -1.301 -0.004)
			(size 0.7 1.2)
			(layers "B.Cu" "B.Paste" "B.Mask")
			(net 1 "GND")
			(pinfunction "GND")
			(pintype "power_in")
		)
		(pad "3" smd rect
			(at -1.301 -0.954)
			(size 0.7 1.2)
			(layers "B.Cu" "B.Paste" "B.Mask")
			(net 311 "CSIA_FLG")
			(pinfunction "FLG")
			(pintype "output")
		)
		(pad "4" smd rect
			(at 1.299 -0.954)
			(size 0.7 1.2)
			(layers "B.Cu" "B.Paste" "B.Mask")
			(net 322 "CSIA_PEN")
			(pinfunction "EN")
			(pintype "input")
		)
		(pad "5" smd rect
			(at 1.299 -0.004)
			(size 0.7 1.2)
			(layers "B.Cu" "B.Paste" "B.Mask")
			(net 334 "/CSI/CSIA_5V_ISET")
			(pinfunction "ISET")
			(pintype "passive")
		)
		(pad "6" smd rect
			(at 1.299 0.947)
			(size 0.7 1.2)
			(layers "B.Cu" "B.Paste" "B.Mask")
			(net 99 "+5V")
			(pinfunction "IN")
			(pintype "power_in")
		)
	)
)
